(kicad_pcb
	(version 20260206)
	(generator "pcbnew")
	(generator_version "10.0")
	(general
		(thickness 1.6)
		(legacy_teardrops no)
	)
	(paper "A4")
	(title_block
		(title "04192023_DAF0TMB3IC0_F0TG_MB_C_brd_V02_OCP.brd")
		(comment 1 "Grand Teton / footprints 872-877 of 8354")
	)
	(layers
		(0 "F.Cu" signal "TOP")
		(4 "In1.Cu" signal "GND")
		(6 "In2.Cu" signal "IN1")
		(8 "In3.Cu" signal "GND1")
		(10 "In4.Cu" signal "IN2")
		(12 "In5.Cu" signal "GND2")
		(14 "In6.Cu" signal "IN3")
		(16 "In7.Cu" signal "GND3")
		(18 "In8.Cu" signal "VCC")
		(20 "In9.Cu" signal "VCC1")
		(22 "In10.Cu" signal "GND4")
		(24 "In11.Cu" signal "IN4")
		(26 "In12.Cu" signal "GND5")
		(28 "In13.Cu" signal "IN5")
		(30 "In14.Cu" signal "GND6")
		(32 "In15.Cu" signal "IN6")
		(34 "In16.Cu" signal "GND7")
		(2 "B.Cu" signal "BOTTOM")
		(9 "F.Adhes" user "F.Adhesive")
		(11 "B.Adhes" user "B.Adhesive")
		(13 "F.Paste" user "Package Geometry/Pastemask Top")
		(15 "B.Paste" user "Package Geometry/Pastemask Bottom")
		(5 "F.SilkS" user "Ref Des/Silkscreen Top")
		(7 "B.SilkS" user "Ref Des/Silkscreen Bottom")
		(1 "F.Mask" user "Board Geometry/Soldermask Top")
		(3 "B.Mask" user "Board Geometry/Soldermask Bottom")
		(17 "Dwgs.User" user "User.Drawings")
		(19 "Cmts.User" user "User.Comments")
		(21 "Eco1.User" user "User.Eco1")
		(23 "Eco2.User" user "User.Eco2")
		(25 "Edge.Cuts" user "Board Geometry/Outline")
		(27 "Margin" user)
		(31 "F.CrtYd" user "Package Geometry/Place Bound Top")
		(29 "B.CrtYd" user "Package Geometry/Place Bound Bottom")
		(35 "F.Fab" user "Ref Des/Assembly Top")
		(33 "B.Fab" user "Ref Des/Assembly Bottom")
	)
	(footprint ""
		(layer "F.Cu")
		(at 234.739688 -152.631648 180)
		(property "Reference" "U13"
			(at -4.649724 -0.803148 0)
			(unlocked yes)
			(layer "F.SilkS")
			(effects
				(font
					(size 0.7874 0.5842)
					(thickness 0.1524)
				)
				(justify left)
			)
		)
		(property "Value" ""
			(at 0 0 180)
			(layer "F.Fab")
			(effects
				(font
					(size 1.27 1.27)
				)
			)
		)
		(duplicate_pad_numbers_are_jumpers no)
		(fp_line
			(start 1.0414 1.575054)
			(end -1.0414 1.575054)
			(stroke
				(width 0.1524)
				(type default)
			)
			(layer "F.SilkS")
		)
		(fp_line
			(start 1.0414 -1.575054)
			(end 1.0414 1.575054)
			(stroke
				(width 0.1524)
				(type default)
			)
			(layer "F.SilkS")
		)
		(fp_line
			(start 0.254 -1.575054)
			(end 1.0414 -1.575054)
			(stroke
				(width 0.1524)
				(type default)
			)
			(layer "F.SilkS")
		)
		(fp_line
			(start 0.2286 -1.575054)
			(end 0 -1.272032)
			(stroke
				(width 0.1524)
				(type default)
			)
			(layer "F.SilkS")
		)
		(fp_line
			(start 0 -1.272032)
			(end -0.254 -1.575054)
			(stroke
				(width 0.1524)
				(type default)
			)
			(layer "F.SilkS")
		)
		(fp_line
			(start -1.0414 1.575054)
			(end -1.0414 -1.575054)
			(stroke
				(width 0.1524)
				(type default)
			)
			(layer "F.SilkS")
		)
		(fp_line
			(start -1.0414 -1.575054)
			(end -0.254 -1.575054)
			(stroke
				(width 0.1524)
				(type default)
			)
			(layer "F.SilkS")
		)
		(fp_poly
			(pts
				(xy -3.600704 -0.436118) (xy -3.600704 -1.452118) (xy -2.584704 -0.944118)
			)
			(stroke
				(width 0)
				(type default)
			)
			(fill yes)
			(layer "F.SilkS")
		)
		(fp_line
			(start 2.5654 1.2192)
			(end 1.4478 1.2192)
			(stroke
				(width 0.1)
				(type default)
			)
			(layer "F.Fab")
		)
		(fp_line
			(start 2.5654 -1.2192)
			(end 2.5654 1.2192)
			(stroke
				(width 0.1)
				(type default)
			)
			(layer "F.Fab")
		)
		(fp_line
			(start 1.4478 1.5748)
			(end -1.4478 1.5748)
			(stroke
				(width 0.1)
				(type default)
			)
			(layer "F.Fab")
		)
		(fp_line
			(start 1.4478 1.2192)
			(end 1.4478 1.5748)
			(stroke
				(width 0.1)
				(type default)
			)
			(layer "F.Fab")
		)
		(fp_line
			(start 1.4478 -1.2192)
			(end 2.5654 -1.2192)
			(stroke
				(width 0.1)
				(type default)
			)
			(layer "F.Fab")
		)
		(fp_line
			(start 1.4478 -1.5748)
			(end 1.4478 -1.2192)
			(stroke
				(width 0.1)
				(type default)
			)
			(layer "F.Fab")
		)
		(fp_line
			(start -1.4478 1.5748)
			(end -1.4478 1.2192)
			(stroke
				(width 0.1)
				(type default)
			)
			(layer "F.Fab")
		)
		(fp_line
			(start -1.4478 1.2192)
			(end -2.5654 1.2192)
			(stroke
				(width 0.1)
				(type default)
			)
			(layer "F.Fab")
		)
		(fp_line
			(start -1.4478 -1.2192)
			(end -1.4478 -1.5748)
			(stroke
				(width 0.1)
				(type default)
			)
			(layer "F.Fab")
		)
		(fp_line
			(start -1.4478 -1.5748)
			(end 1.4478 -1.5748)
			(stroke
				(width 0.1)
				(type default)
			)
			(layer "F.Fab")
		)
		(fp_line
			(start -2.5654 1.2192)
			(end -2.5654 -1.2192)
			(stroke
				(width 0.1)
				(type default)
			)
			(layer "F.Fab")
		)
		(fp_line
			(start -2.5654 -1.2192)
			(end -1.4478 -1.2192)
			(stroke
				(width 0.1)
				(type default)
			)
			(layer "F.Fab")
		)
		(fp_poly
			(pts
				(xy -2.710688 -0.975106) (xy -3.726688 -1.483106) (xy -3.726688 -0.467106)
			)
			(stroke
				(width 0)
				(type default)
			)
			(fill yes)
			(layer "F.Fab")
		)
		(pad "1" smd rect
			(at -1.849882 -0.975106 90)
			(size 0.3556 1.3208)
			(layers "F.Cu" "F.Mask" "F.Paste")
			(net "JTAG_CPU0_TDO")
		)
		(pad "2" smd rect
			(at -1.849882 -0.32512 90)
			(size 0.3556 1.3208)
			(layers "F.Cu" "F.Mask" "F.Paste")
			(net "JTAG_CPU0_TDO_CPU1_TDI")
		)
		(pad "3" smd rect
			(at -1.849882 0.32512 90)
			(size 0.3556 1.3208)
			(layers "F.Cu" "F.Mask" "F.Paste")
			(net "FM_PLD_CPU0_PRSNT_HDT_N")
		)
		(pad "4" smd rect
			(at -1.849882 0.975106 90)
			(size 0.3556 1.3208)
			(layers "F.Cu" "F.Mask" "F.Paste")
			(net "GND")
		)
		(pad "5" smd rect
			(at 1.849882 0.975106 90)
			(size 0.3556 1.3208)
			(layers "F.Cu" "F.Mask" "F.Paste")
			(net "JTAG_CPU0_BYPASS_R1")
		)
		(pad "6" smd rect
			(at 1.849882 0.32512 90)
			(size 0.3556 1.3208)
			(layers "F.Cu" "F.Mask" "F.Paste")
			(net "JTAG_CPU0_TDO_CPU1_TDI_R1")
		)
		(pad "7" smd rect
			(at 1.849882 -0.32512 90)
			(size 0.3556 1.3208)
			(layers "F.Cu" "F.Mask" "F.Paste")
			(net "CPU0_HDT_BYPASS_SEL")
		)
		(pad "8" smd rect
			(at 1.849882 -0.975106 90)
			(size 0.3556 1.3208)
			(layers "F.Cu" "F.Mask" "F.Paste")
			(net "PVDD18_S5_P0")
		)
	)
	(footprint ""
		(layer "F.Cu")
		(at 40.386 -436.499)
		(property "Reference" "U256"
			(at -0.413004 -3.526282 0)
			(unlocked yes)
			(layer "F.SilkS")
			(effects
				(font
					(size 0.7874 0.5842)
					(thickness 0.1524)
				)
				(justify left)
			)
		)
		(property "Value" ""
			(at 0 0 0)
			(layer "F.Fab")
			(effects
				(font
					(size 1.27 1.27)
				)
			)
		)
		(duplicate_pad_numbers_are_jumpers no)
		(fp_line
			(start -1.3462 -1.100074)
			(end -0.670052 -1.100074)
			(stroke
				(width 0.1524)
				(type default)
			)
			(layer "F.SilkS")
		)
		(fp_line
			(start -1.3462 1.100074)
			(end -1.3462 -1.100074)
			(stroke
				(width 0.1524)
				(type default)
			)
			(layer "F.SilkS")
		)
		(fp_line
			(start -0.670052 -1.100074)
			(end 0 -0.381)
			(stroke
				(width 0.1524)
				(type default)
			)
			(layer "F.SilkS")
		)
		(fp_line
			(start 0 -0.381)
			(end 0.670052 -1.100074)
			(stroke
				(width 0.1524)
				(type default)
			)
			(layer "F.SilkS")
		)
		(fp_line
			(start 0.670052 -1.100074)
			(end 1.3462 -1.100074)
			(stroke
				(width 0.1524)
				(type default)
			)
			(layer "F.SilkS")
		)
		(fp_line
			(start 1.3462 -1.100074)
			(end 1.3462 1.100074)
			(stroke
				(width 0.1524)
				(type default)
			)
			(layer "F.SilkS")
		)
		(fp_line
			(start 1.3462 1.100074)
			(end -1.3462 1.100074)
			(stroke
				(width 0.1524)
				(type default)
			)
			(layer "F.SilkS")
		)
		(fp_poly
			(pts
				(xy -2.620518 -1.867408) (xy -2.160778 -2.474976) (xy -1.78308 -1.711198)
			)
			(stroke
				(width 0)
				(type default)
			)
			(fill yes)
			(layer "F.SilkS")
		)
		(fp_line
			(start -1.100074 -0.8001)
			(end -0.670052 -0.8001)
			(stroke
				(width 0.1)
				(type default)
			)
			(layer "F.Fab")
		)
		(fp_line
			(start -1.100074 0.8001)
			(end -1.100074 -0.8001)
			(stroke
				(width 0.1)
				(type default)
			)
			(layer "F.Fab")
		)
		(fp_line
			(start -0.670052 -1.100074)
			(end 0.670052 -1.100074)
			(stroke
				(width 0.1)
				(type default)
			)
			(layer "F.Fab")
		)
		(fp_line
			(start -0.670052 -0.8001)
			(end -0.670052 -1.100074)
			(stroke
				(width 0.1)
				(type default)
			)
			(layer "F.Fab")
		)
		(fp_line
			(start -0.670052 0.8001)
			(end -1.100074 0.8001)
			(stroke
				(width 0.1)
				(type default)
			)
			(layer "F.Fab")
		)
		(fp_line
			(start -0.670052 0.8001)
			(end -0.670052 -0.8001)
			(stroke
				(width 0.1)
				(type default)
			)
			(layer "F.Fab")
		)
		(fp_line
			(start -0.670052 1.100074)
			(end -0.670052 0.8001)
			(stroke
				(width 0.1)
				(type default)
			)
			(layer "F.Fab")
		)
		(fp_line
			(start 0.670052 -1.100074)
			(end 0.670052 -0.8001)
			(stroke
				(width 0.1)
				(type default)
			)
			(layer "F.Fab")
		)
		(fp_line
			(start 0.670052 -0.8001)
			(end 0.670052 0.8001)
			(stroke
				(width 0.1)
				(type default)
			)
			(layer "F.Fab")
		)
		(fp_line
			(start 0.670052 -0.8001)
			(end 1.100074 -0.8001)
			(stroke
				(width 0.1)
				(type default)
			)
			(layer "F.Fab")
		)
		(fp_line
			(start 0.670052 0.8001)
			(end 0.670052 1.100074)
			(stroke
				(width 0.1)
				(type default)
			)
			(layer "F.Fab")
		)
		(fp_line
			(start 0.670052 1.100074)
			(end -0.670052 1.100074)
			(stroke
				(width 0.1)
				(type default)
			)
			(layer "F.Fab")
		)
		(fp_line
			(start 1.100074 -0.8001)
			(end 1.100074 0.8001)
			(stroke
				(width 0.1)
				(type default)
			)
			(layer "F.Fab")
		)
		(fp_line
			(start 1.100074 0.8001)
			(end 0.670052 0.8001)
			(stroke
				(width 0.1)
				(type default)
			)
			(layer "F.Fab")
		)
		(fp_poly
			(pts
				(xy -1.524 -0.649986) (xy -2.286 -1.030986) (xy -2.286 -0.268986)
			)
			(stroke
				(width 0)
				(type default)
			)
			(fill yes)
			(layer "F.Fab")
		)
		(pad "1" smd rect
			(at -0.94996 -0.649986 270)
			(size 0.4064 0.508)
			(layers "F.Cu" "F.Mask" "F.Paste")
			(net "RST_PERST_CPU0_SWB_R_N")
		)
		(pad "2" smd rect
			(at -0.94996 0 270)
			(size 0.4064 0.508)
			(layers "F.Cu" "F.Mask" "F.Paste")
			(net "GND")
		)
		(pad "3" smd rect
			(at -0.94996 0.649986 270)
			(size 0.4064 0.508)
			(layers "F.Cu" "F.Mask" "F.Paste")
			(net "FM_SWB_PWR_EN_R")
		)
		(pad "4" smd rect
			(at 0.94996 0.649986 270)
			(size 0.4064 0.508)
			(layers "F.Cu" "F.Mask" "F.Paste")
			(net "FM_SWB_PWR_EN_R1_BUF")
		)
		(pad "5" smd rect
			(at 0.94996 0 270)
			(size 0.4064 0.508)
			(layers "F.Cu" "F.Mask" "F.Paste")
			(net "P3V3_AUX")
		)
		(pad "6" smd rect
			(at 0.94996 -0.649986 270)
			(size 0.4064 0.508)
			(layers "F.Cu" "F.Mask" "F.Paste")
			(net "RST_PERST_1_SWB_BUF_R_N")
		)
	)
	(footprint ""
		(layer "F.Cu")
		(at 393.1031 -185.748168)
		(property "Reference" "PC181"
			(at 0 0 0)
			(layer "F.SilkS")
			(hide yes)
			(effects
				(font
					(size 1.27 1.27)
				)
			)
		)
		(property "Value" ""
			(at 0 0 0)
			(layer "F.Fab")
			(effects
				(font
					(size 1.27 1.27)
				)
			)
		)
		(duplicate_pad_numbers_are_jumpers no)
		(fp_line
			(start -0.7874 -0.4064)
			(end 0.7874 -0.4064)
			(stroke
				(width 0.1524)
				(type default)
			)
			(layer "F.SilkS")
		)
		(fp_line
			(start -0.7874 0.4064)
			(end -0.7874 -0.4064)
			(stroke
				(width 0.1524)
				(type default)
			)
			(layer "F.SilkS")
		)
		(fp_line
			(start 0.7874 -0.4064)
			(end 0.7874 0.4064)
			(stroke
				(width 0.1524)
				(type default)
			)
			(layer "F.SilkS")
		)
		(fp_line
			(start 0.7874 0.4064)
			(end -0.7874 0.4064)
			(stroke
				(width 0.1524)
				(type default)
			)
			(layer "F.SilkS")
		)
		(fp_line
			(start -0.67945 -0.305054)
			(end -0.12065 -0.305054)
			(stroke
				(width 0.1)
				(type default)
			)
			(layer "F.Fab")
		)
		(fp_line
			(start -0.67945 0.3048)
			(end -0.67945 -0.305054)
			(stroke
				(width 0.1)
				(type default)
			)
			(layer "F.Fab")
		)
		(fp_line
			(start -0.12065 -0.305054)
			(end -0.12065 -0.2794)
			(stroke
				(width 0.1)
				(type default)
			)
			(layer "F.Fab")
		)
		(fp_line
			(start -0.12065 -0.2794)
			(end 0.12065 -0.2794)
			(stroke
				(width 0.1)
				(type default)
			)
			(layer "F.Fab")
		)
		(fp_line
			(start -0.12065 0.2794)
			(end -0.12065 0.3048)
			(stroke
				(width 0.1)
				(type default)
			)
			(layer "F.Fab")
		)
		(fp_line
			(start -0.12065 0.3048)
			(end -0.67945 0.3048)
			(stroke
				(width 0.1)
				(type default)
			)
			(layer "F.Fab")
		)
		(fp_line
			(start 0.120396 0.2794)
			(end -0.12065 0.2794)
			(stroke
				(width 0.1)
				(type default)
			)
			(layer "F.Fab")
		)
		(fp_line
			(start 0.120396 0.3048)
			(end 0.120396 0.2794)
			(stroke
				(width 0.1)
				(type default)
			)
			(layer "F.Fab")
		)
		(fp_line
			(start 0.12065 -0.3048)
			(end 0.67945 -0.3048)
			(stroke
				(width 0.1)
				(type default)
			)
			(layer "F.Fab")
		)
		(fp_line
			(start 0.12065 -0.2794)
			(end 0.12065 -0.3048)
			(stroke
				(width 0.1)
				(type default)
			)
			(layer "F.Fab")
		)
		(fp_line
			(start 0.67945 -0.3048)
			(end 0.67945 0.3048)
			(stroke
				(width 0.1)
				(type default)
			)
			(layer "F.Fab")
		)
		(fp_line
			(start 0.67945 0.3048)
			(end 0.120396 0.3048)
			(stroke
				(width 0.1)
				(type default)
			)
			(layer "F.Fab")
		)
		(pad "1" smd circle
			(at -0.40005 0)
			(size 0 0)
			(layers "F.Cu" "F.Mask" "F.Paste")
			(net "SW_PVDDCR_CPU0_P0_SW4")
		)
		(pad "2" smd circle
			(at 0.40005 0)
			(size 0 0)
			(layers "F.Cu" "F.Mask" "F.Paste")
			(net "SW_PVDDCR_CPU0_P0_SW4_RC")
		)
	)
	(footprint ""
		(layer "F.Cu")
		(at 416.373564 -17.624298 90)
		(property "Reference" "C47"
			(at 0 0 90)
			(layer "F.SilkS")
			(hide yes)
			(effects
				(font
					(size 1.27 1.27)
				)
			)
		)
		(property "Value" ""
			(at 0 0 90)
			(layer "F.Fab")
			(effects
				(font
					(size 1.27 1.27)
				)
			)
		)
		(duplicate_pad_numbers_are_jumpers no)
		(fp_line
			(start 0.299974 -0.150114)
			(end 0.299974 0.150114)
			(stroke
				(width 0.1)
				(type default)
			)
			(layer "F.Fab")
		)
		(fp_line
			(start -0.299974 -0.150114)
			(end 0.299974 -0.150114)
			(stroke
				(width 0.1)
				(type default)
			)
			(layer "F.Fab")
		)
		(fp_line
			(start 0.299974 0.150114)
			(end -0.299974 0.150114)
			(stroke
				(width 0.1)
				(type default)
			)
			(layer "F.Fab")
		)
		(fp_line
			(start -0.299974 0.150114)
			(end -0.299974 -0.150114)
			(stroke
				(width 0.1)
				(type default)
			)
			(layer "F.Fab")
		)
		(pad "1" smd rect
			(at -0.2667 0 90)
			(size 0.3048 0.381)
			(layers "F.Cu" "F.Mask" "F.Paste")
			(net "P5E_CPU0_G3_TX_C_DP<6>")
		)
		(pad "2" smd rect
			(at 0.2667 0 90)
			(size 0.3048 0.381)
			(layers "F.Cu" "F.Mask" "F.Paste")
			(net "P5E_CPU0_G3_TX_DP<6>")
		)
	)
	(footprint ""
		(layer "F.Cu")
		(at 336.172556 -135.50265)
		(property "Reference" "PC111"
			(at 0 0 0)
			(layer "F.SilkS")
			(hide yes)
			(effects
				(font
					(size 1.27 1.27)
				)
			)
		)
		(property "Value" ""
			(at 0 0 0)
			(layer "F.Fab")
			(effects
				(font
					(size 1.27 1.27)
				)
			)
		)
		(duplicate_pad_numbers_are_jumpers no)
		(fp_line
			(start -1.524 -0.762)
			(end 1.524 -0.762)
			(stroke
				(width 0.1524)
				(type default)
			)
			(layer "F.SilkS")
		)
		(fp_line
			(start -1.524 0.762)
			(end -1.524 -0.762)
			(stroke
				(width 0.1524)
				(type default)
			)
			(layer "F.SilkS")
		)
		(fp_line
			(start 1.524 -0.762)
			(end 1.524 0.762)
			(stroke
				(width 0.1524)
				(type default)
			)
			(layer "F.SilkS")
		)
		(fp_line
			(start 1.524 0.762)
			(end -1.524 0.762)
			(stroke
				(width 0.1524)
				(type default)
			)
			(layer "F.SilkS")
		)
		(fp_line
			(start -1.1049 -0.724916)
			(end -1.1049 0.724916)
			(stroke
				(width 0.1)
				(type default)
			)
			(layer "F.Fab")
		)
		(fp_line
			(start -1.1049 0.724916)
			(end 1.1049 0.724916)
			(stroke
				(width 0.1)
				(type default)
			)
			(layer "F.Fab")
		)
		(fp_line
			(start 1.1049 -0.724916)
			(end -1.1049 -0.724916)
			(stroke
				(width 0.1)
				(type default)
			)
			(layer "F.Fab")
		)
		(fp_line
			(start 1.1049 0.724916)
			(end 1.1049 -0.724916)
			(stroke
				(width 0.1)
				(type default)
			)
			(layer "F.Fab")
		)
		(pad "1" smd rect
			(at -0.889 0 180)
			(size 1.016 1.27)
			(layers "F.Cu" "F.Mask" "F.Paste")
			(net "SW_P12V_AUX_PVDD18_S5_P0_FLT")
		)
		(pad "2" smd rect
			(at 0.889 0 180)
			(size 1.016 1.27)
			(layers "F.Cu" "F.Mask" "F.Paste")
			(net "GND")
		)
	)
	(footprint ""
		(layer "F.Cu")
		(at 303.768506 -416.899344 -90)
		(property "Reference" "C6502"
			(at 0 0 270)
			(layer "F.SilkS")
			(hide yes)
			(effects
				(font
					(size 1.27 1.27)
				)
			)
		)
		(property "Value" ""
			(at 0 0 270)
			(layer "F.Fab")
			(effects
				(font
					(size 1.27 1.27)
				)
			)
		)
		(duplicate_pad_numbers_are_jumpers no)
		(fp_line
			(start -0.299974 0.150114)
			(end -0.299974 -0.150114)
			(stroke
				(width 0.1)
				(type default)
			)
			(layer "F.Fab")
		)
		(fp_line
			(start 0.299974 0.150114)
			(end -0.299974 0.150114)
			(stroke
				(width 0.1)
				(type default)
			)
			(layer "F.Fab")
		)
		(fp_line
			(start -0.299974 -0.150114)
			(end 0.299974 -0.150114)
			(stroke
				(width 0.1)
				(type default)
			)
			(layer "F.Fab")
		)
		(fp_line
			(start 0.299974 -0.150114)
			(end 0.299974 0.150114)
			(stroke
				(width 0.1)
				(type default)
			)
			(layer "F.Fab")
		)
		(pad "1" smd rect
			(at -0.2667 0 270)
			(size 0.3048 0.381)
			(layers "F.Cu" "F.Mask" "F.Paste")
			(net "P5E_CPU0_P0_TX_BUF_C_DN<0>")
		)
		(pad "2" smd rect
			(at 0.2667 0 270)
			(size 0.3048 0.381)
			(layers "F.Cu" "F.Mask" "F.Paste")
			(net "P5E_CPU0_P0_TX_BUF_DN<0>")
		)
	)
)
